# BASEBOARD_FAB2 (Tioga Pass) — schematic netlist excerpt (pin names and nets, part order shuffled) for the footprints in the layout excerpt that follows; sources: Cadence DE-HDL packaged netlist, KiCad conversion of Wiwynn_Tioga_Pass_MB.brd

R7F18  RES  7.87K 1.0% CHIP  pkg 0402  page 231 : A = VR_COMP_RC_PVPP_ABC ; B = VR_FB_PVPP_ABC
R1U60  RES  0.0 5% CHIP  pkg 0402  page 152 : A = H_CPU1_MEMKLM_MEMHOT_G_N ; B = H_CPU1_MEMKLM_MEMHOT_G_R_N
TH4A1  MTG_KEYHOLE  EMPTY  pkg TH  page 195 : \1\ = GND

(kicad_pcb
	(version 20260206)
	(generator "pcbnew")
	(generator_version "10.0")
	(general
		(thickness 1.6)
		(legacy_teardrops no)
	)
	(paper "A4")
	(title_block
		(title "Wiwynn_Tioga_Pass_MB.brd")
		(comment 1 "Tioga Pass / footprints 1658-1660 of 4770")
	)
	(layers
		(0 "F.Cu" signal "TOP")
		(4 "In1.Cu" signal "L2GND")
		(6 "In2.Cu" signal "L3")
		(8 "In3.Cu" signal "L4GND")
		(10 "In4.Cu" signal "L5")
		(12 "In5.Cu" signal "L6GND")
		(14 "In6.Cu" signal "L7VCC")
		(16 "In7.Cu" signal "L8VCC")
		(18 "In8.Cu" signal "L9GND")
		(20 "In9.Cu" signal "L10")
		(22 "In10.Cu" signal "L11GND")
		(24 "In11.Cu" signal "L12")
		(26 "In12.Cu" signal "L13GND")
		(2 "B.Cu" signal "BOTTOM")
		(9 "F.Adhes" user "F.Adhesive")
		(11 "B.Adhes" user "B.Adhesive")
		(13 "F.Paste" user "Package Geometry/Pastemask Top")
		(15 "B.Paste" user "Package Geometry/Pastemask Bottom")
		(5 "F.SilkS" user "Ref Des/Silkscreen Top")
		(7 "B.SilkS" user "Ref Des/Silkscreen Bottom")
		(1 "F.Mask" user "Board Geometry/Soldermask Top")
		(3 "B.Mask" user "Board Geometry/Soldermask Bottom")
		(17 "Dwgs.User" user "User.Drawings")
		(19 "Cmts.User" user "User.Comments")
		(21 "Eco1.User" user "User.Eco1")
		(23 "Eco2.User" user "User.Eco2")
		(25 "Edge.Cuts" user "Board Geometry/Outline")
		(27 "Margin" user)
		(31 "F.CrtYd" user "Package Geometry/Place Bound Top")
		(29 "B.CrtYd" user "Package Geometry/Place Bound Bottom")
		(35 "F.Fab" user "Ref Des/Assembly Top")
		(33 "B.Fab" user "Ref Des/Assembly Bottom")
	)
	(footprint ""
		(layer "F.Cu")
		(at 171.99991 -155.10002 90)
		(property "Reference" "TH4A1"
			(at -0.94869 -7.15391 0)
			(unlocked yes)
			(layer "F.SilkS")
			(effects
				(font
					(size 0.7874 0.5842)
					(thickness 0.1524)
				)
				(justify left)
			)
		)
		(property "Value" ""
			(at 0 0 90)
			(layer "F.Fab")
			(effects
				(font
					(size 1.27 1.27)
				)
			)
		)
		(duplicate_pad_numbers_are_jumpers no)
		(fp_poly
			(pts
				(arc
					(start 3.0226 0.68834)
					(mid 3.042235 0.827855)
					(end 3.099562 0.956564)
				)
				(arc
					(start 3.099562 0.956564)
					(mid 4.012804 3.550073)
					(end 3.042158 6.12267)
				)
				(arc
					(start 3.042158 6.12267)
					(mid 0 7.518589)
					(end -3.042158 6.12267)
				)
				(arc
					(start -3.042158 6.12267)
					(mid -4.012854 3.55061)
					(end -3.100324 0.957326)
				)
				(arc
					(start -3.100324 0.957326)
					(mid -3.042498 0.827518)
					(end -3.0226 0.686816)
				)
				(arc
					(start -3.0226 -0.000254)
					(mid -2.137121 -2.137227)
					(end 0 -3.022346)
				)
				(arc
					(start 0 -3.022346)
					(mid 2.137227 -2.136973)
					(end 3.0226 0.000254)
				)
			)
			(stroke
				(width 0)
				(type default)
			)
			(fill no)
			(layer "F.CrtYd")
		)
		(pad "1" thru_hole custom
			(at 0 0 90)
			(size 2.00667 2.00667)
			(drill 0.3048)
			(layers "*.Cu" "*.Mask")
			(remove_unused_layers no)
			(net "GND")
			(clearance -0.889)
			(options
				(clearance outline)
				(anchor circle)
			)
			(primitives
				(gr_poly
					(pts
						(arc
							(start 3.042158 3.874516)
							(mid 0 5.270435)
							(end -3.042158 3.874516)
						)
						(arc
							(start -3.042158 3.874516)
							(mid -4.012854 1.302456)
							(end -3.100324 -1.290828)
						)
						(arc
							(start -3.100324 -1.290828)
							(mid -3.042498 -1.420636)
							(end -3.0226 -1.561338)
						)
						(arc
							(start -3.0226 -2.248408)
							(mid -2.137121 -4.385381)
							(end 0 -5.2705)
						)
						(arc
							(start 0 -5.2705)
							(mid 2.137227 -4.385127)
							(end 3.0226 -2.2479)
						)
						(arc
							(start 3.0226 -1.55956)
							(mid 3.04227 -1.420177)
							(end 3.099562 -1.29159)
						)
						(arc
							(start 3.099562 -1.29159)
							(mid 4.012804 1.301919)
							(end 3.042158 3.874516)
						)
					)
					(width 0)
					(fill yes)
				)
			)
		)
	)
	(footprint ""
		(layer "F.Cu")
		(at 438.4675 -16.129 90)
		(property "Reference" "R1U60"
			(at 0 0 90)
			(layer "F.SilkS")
			(hide yes)
			(effects
				(font
					(size 1.27 1.27)
				)
			)
		)
		(property "Value" ""
			(at 0 0 90)
			(layer "F.Fab")
			(effects
				(font
					(size 1.27 1.27)
				)
			)
		)
		(duplicate_pad_numbers_are_jumpers no)
		(fp_poly
			(pts
				(xy -0.2794 -0.1016) (xy 0.2794 -0.1016) (xy 0.2794 0.9906) (xy -0.2794 0.9906)
			)
			(stroke
				(width 0)
				(type default)
			)
			(fill no)
			(layer "F.CrtYd")
		)
		(fp_line
			(start 0.2794 -0.1016)
			(end -0.2794 -0.1016)
			(stroke
				(width 0.1)
				(type default)
			)
			(layer "F.Fab")
		)
		(fp_line
			(start -0.2794 -0.1016)
			(end -0.2794 0.9906)
			(stroke
				(width 0.1)
				(type default)
			)
			(layer "F.Fab")
		)
		(fp_line
			(start 0.2794 0.9906)
			(end 0.2794 -0.1016)
			(stroke
				(width 0.1)
				(type default)
			)
			(layer "F.Fab")
		)
		(fp_line
			(start -0.2794 0.9906)
			(end 0.2794 0.9906)
			(stroke
				(width 0.1)
				(type default)
			)
			(layer "F.Fab")
		)
		(pad "1" smd rect
			(at 0 0 90)
			(size 0.508 0.508)
			(layers "F.Cu" "F.Mask" "F.Paste")
			(net "H_CPU1_MEMKLM_MEMHOT_G_N")
		)
		(pad "2" smd rect
			(at 0 0.889 90)
			(size 0.508 0.508)
			(layers "F.Cu" "F.Mask" "F.Paste")
			(net "H_CPU1_MEMKLM_MEMHOT_G_R_N")
		)
		(zone
			(layer "F.Cu")
			(hatch none 0.5)
			(connect_pads
				(clearance 0)
			)
			(min_thickness 0.25)
			(keepout
				(tracks allowed)
				(vias not_allowed)
				(pads allowed)
				(copperpour not_allowed)
				(footprints allowed)
			)
			(placement
				(enabled no)
				(sheetname "")
			)
			(fill
				(thermal_gap 0.5)
				(thermal_bridge_width 0.5)
				(island_removal_mode 0)
			)
			(polygon
				(pts
					(xy 438.7215 -15.875) (xy 438.7215 -16.383) (xy 439.1025 -16.383) (xy 439.1025 -15.875)
				)
			)
		)
		(zone
			(layer "F.Cu")
			(hatch none 0.5)
			(connect_pads
				(clearance 0)
			)
			(min_thickness 0.25)
			(keepout
				(tracks not_allowed)
				(vias allowed)
				(pads allowed)
				(copperpour not_allowed)
				(footprints allowed)
			)
			(placement
				(enabled no)
				(sheetname "")
			)
			(fill
				(thermal_gap 0.5)
				(thermal_bridge_width 0.5)
				(island_removal_mode 0)
			)
			(polygon
				(pts
					(xy 439.1025 -15.875) (xy 439.1025 -16.383) (xy 438.7215 -16.383) (xy 438.7215 -15.875)
				)
			)
		)
	)
	(footprint ""
		(layer "F.Cu")
		(at 343.027 -22.64156 180)
		(property "Reference" "R7F18"
			(at 0 0 180)
			(layer "F.SilkS")
			(hide yes)
			(effects
				(font
					(size 1.27 1.27)
				)
			)
		)
		(property "Value" ""
			(at 0 0 180)
			(layer "F.Fab")
			(effects
				(font
					(size 1.27 1.27)
				)
			)
		)
		(duplicate_pad_numbers_are_jumpers no)
		(fp_rect
			(start 0.2794 -0.1016)
			(end -0.2794 0.9906)
			(stroke
				(width 0)
				(type default)
			)
			(fill no)
			(layer "F.CrtYd")
		)
		(fp_line
			(start 0.2794 0.9906)
			(end 0.2794 -0.1016)
			(stroke
				(width 0.1)
				(type default)
			)
			(layer "F.Fab")
		)
		(fp_line
			(start 0.2794 -0.1016)
			(end -0.2794 -0.1016)
			(stroke
				(width 0.1)
				(type default)
			)
			(layer "F.Fab")
		)
		(fp_line
			(start -0.2794 0.9906)
			(end 0.2794 0.9906)
			(stroke
				(width 0.1)
				(type default)
			)
			(layer "F.Fab")
		)
		(fp_line
			(start -0.2794 -0.1016)
			(end -0.2794 0.9906)
			(stroke
				(width 0.1)
				(type default)
			)
			(layer "F.Fab")
		)
		(pad "1" smd rect
			(at 0 0 180)
			(size 0.508 0.508)
			(layers "F.Cu" "F.Mask" "F.Paste")
			(net "VR_COMP_RC_PVPP_ABC")
		)
		(pad "2" smd rect
			(at 0 0.889 180)
			(size 0.508 0.508)
			(layers "F.Cu" "F.Mask" "F.Paste")
			(net "VR_FB_PVPP_ABC")
		)
		(zone
			(layer "F.Cu")
			(hatch none 0.5)
			(connect_pads
				(clearance 0)
			)
			(min_thickness 0.25)
			(keepout
				(tracks allowed)
				(vias not_allowed)
				(pads allowed)
				(copperpour not_allowed)
				(footprints allowed)
			)
			(placement
				(enabled no)
				(sheetname "")
			)
			(fill
				(thermal_gap 0.5)
				(thermal_bridge_width 0.5)
				(island_removal_mode 0)
			)
			(polygon
				(pts
					(xy 342.773 -22.89556) (xy 343.281 -22.89556) (xy 343.281 -23.27656) (xy 342.773 -23.27656)
				)
			)
		)
		(zone
			(layer "F.Cu")
			(hatch none 0.5)
			(connect_pads
				(clearance 0)
			)
			(min_thickness 0.25)
			(keepout
				(tracks not_allowed)
				(vias allowed)
				(pads allowed)
				(copperpour not_allowed)
				(footprints allowed)
			)
			(placement
				(enabled no)
				(sheetname "")
			)
			(fill
				(thermal_gap 0.5)
				(thermal_bridge_width 0.5)
				(island_removal_mode 0)
			)
			(polygon
				(pts
					(xy 342.773 -22.89556) (xy 343.281 -22.89556) (xy 343.281 -23.27656) (xy 342.773 -23.27656)
				)
			)
		)
	)
)
